G04 ================== begin FILE IDENTIFICATION RECORD ==================*
G04 Layout Name:  12523-1.brd*
G04 Film Name:    BMASK*
G04 File Format:  Gerber RS274X*
G04 File Origin:  Cadence Allegro 16.2-s031*
G04 Origin Date:  Fri Oct 19 14:59:05 2012*
G04 *
G04 Layer:  VIA CLASS/SOLDERMASK_BOTTOM*
G04 Layer:  PIN/SOLDERMASK_BOTTOM*
G04 Layer:  PACKAGE GEOMETRY/SOLDERMASK_BOTTOM*
G04 Layer:  DRAWING FORMAT/LAYER_PCB_STORY*
G04 Layer:  DRAWING FORMAT/LAYER_SOLDER_B*
G04 Layer:  BOARD GEOMETRY/SOLDERMASK_BOTTOM*
G04 *
G04 Offset:    (0.00 0.00)*
G04 Mirror:    No*
G04 Mode:      Positive*
G04 Rotation:  0*
G04 FullContactRelief:  No*
G04 UndefLineWidth:     6.00*
G04 ================== end FILE IDENTIFICATION RECORD ====================*
%FSLAX35Y35*MOIN*%
%IR0*IPPOS*OFA0.00000B0.00000*MIA0B0*SFA1.00000B1.00000*%
%ADD18C,.034*%
%ADD19C,.053*%
%ADD15R,.197X.032*%
%ADD16C,.028*%
%ADD17C,.057*%
%ADD10C,.086*%
%ADD14R,.248X.165*%
%ADD13R,.248X.372*%
%ADD11C,.355*%
%ADD20C,.158*%
%ADD12R,.16X.16*%
%ADD21C,.02*%
%ADD22C,.006*%
G75*
%LPD*%
G75*
G36*
G01X-43611Y110602D02*
X-12605D01*
Y291274D01*
X-17705D01*
Y366242D01*
X-43611D01*
Y110602D01*
G37*
G54D10*
X-23621Y15748D03*
Y937008D03*
X1312285Y15747D03*
G54D20*
X600709Y136909D03*
Y311909D03*
G54D11*
X30157Y61023D03*
Y415354D03*
X498661Y23622D03*
X589212Y448818D03*
G54D21*
G01X-4246Y-109426D02*
Y-189426D01*
G01D02*
X1290354D01*
G01X-4246Y-144926D02*
X1290354D01*
G01X-8246Y-93426D02*
G02I-12000J0D01*
G01X-13396D02*
G02I-6850J0D01*
G01X-20246Y-109426D02*
Y-77426D01*
G01X-4246Y-93426D02*
X-36246D01*
G01X-4246Y-109426D02*
X1290354D01*
G01X502854D02*
Y-189426D01*
G01X640354Y-109426D02*
Y-189426D01*
G01X755354Y-109426D02*
Y-189426D01*
G01X922854Y-109426D02*
Y-189426D01*
G01X1092854Y-109426D02*
Y-189426D01*
G01X1290354Y-109426D02*
Y-189426D01*
G01X1318354Y-93426D02*
G02I-12000J0D01*
G01X1313204D02*
G02I-6850J0D01*
G01X1306354Y-109426D02*
Y-77426D01*
G01X1322354Y-93426D02*
X1290354D01*
G54D12*
X-23622Y62794D03*
Y916269D03*
X1297695Y58466D03*
G54D22*
G01X16751Y-179426D02*
Y-161926D01*
G01X25047D02*
X16751Y-172718D01*
G01X26357Y-179426D02*
X20462Y-167760D01*
G01X34032Y-179426D02*
Y-161926D01*
X44076Y-179426D01*
Y-161926D01*
G01X56554Y-179426D02*
X54807Y-179134D01*
X53279Y-177968D01*
X51969Y-176218D01*
X51095Y-174176D01*
X50659Y-171843D01*
Y-169509D01*
X51095Y-167176D01*
X51969Y-165134D01*
X53279Y-163385D01*
X54807Y-162218D01*
X56554Y-161926D01*
X58300Y-162218D01*
X59829Y-163385D01*
X61139Y-165134D01*
X62013Y-167176D01*
X62449Y-169509D01*
Y-171843D01*
X62013Y-174176D01*
X61139Y-176218D01*
X59829Y-177968D01*
X58300Y-179134D01*
X56554Y-179426D01*
G01X69469D02*
X78639Y-161926D01*
G01X69469D02*
X78639Y-179426D01*
G01X104687D02*
Y-161926D01*
X109927D01*
X111674Y-162801D01*
X112984Y-164843D01*
X113421Y-167176D01*
X112984Y-169509D01*
X111892Y-171259D01*
X109927Y-172135D01*
X104687D01*
G01X126554Y-179426D02*
X124807Y-179134D01*
X123279Y-177968D01*
X121969Y-176218D01*
X121095Y-174176D01*
X120659Y-171843D01*
Y-169509D01*
X121095Y-167176D01*
X121969Y-165134D01*
X123279Y-163385D01*
X124807Y-162218D01*
X126554Y-161926D01*
X128300Y-162218D01*
X129829Y-163385D01*
X131139Y-165134D01*
X132013Y-167176D01*
X132449Y-169509D01*
Y-171843D01*
X132013Y-174176D01*
X131139Y-176218D01*
X129829Y-177968D01*
X128300Y-179134D01*
X126554Y-179426D01*
G01X137504Y-161926D02*
X140560Y-179426D01*
X144054Y-161926D01*
X147547Y-179426D01*
X150604Y-161926D01*
G01X165921Y-179426D02*
X157187D01*
Y-161926D01*
X165921D01*
G01X162427Y-170384D02*
X157187D01*
G01X174687Y-179426D02*
Y-161926D01*
X180146D01*
X181892Y-162801D01*
X182984Y-163968D01*
X183421Y-166301D01*
X182984Y-168635D01*
X181674Y-170093D01*
X180146Y-170968D01*
X174687D01*
G01X180146D02*
X183421Y-179426D01*
G01X214054Y-161926D02*
Y-179426D01*
G01X209032Y-161926D02*
X219076D01*
G01X227187Y-179426D02*
Y-161926D01*
X232646D01*
X234392Y-162801D01*
X235484Y-163968D01*
X235921Y-166301D01*
X235484Y-168635D01*
X234174Y-170093D01*
X232646Y-170968D01*
X227187D01*
G01X232646D02*
X235921Y-179426D01*
G01X243595D02*
X249054Y-161926D01*
X254513Y-179426D01*
G01X252547Y-173301D02*
X245560D01*
G01X261532Y-179426D02*
Y-161926D01*
X271576Y-179426D01*
Y-161926D01*
G01X279469Y-177093D02*
X281216Y-178551D01*
X283181Y-179426D01*
X284927D01*
X286674Y-178551D01*
X287984Y-177093D01*
X288639Y-175051D01*
X288202Y-173010D01*
X287111Y-171259D01*
X285146Y-170093D01*
X282526Y-169509D01*
X280997Y-168343D01*
X280342Y-166301D01*
X280779Y-164259D01*
X281871Y-162801D01*
X283399Y-161926D01*
X284927D01*
X286456Y-162509D01*
X287766Y-163968D01*
G01X298934Y-161926D02*
X304174D01*
G01X301554D02*
Y-179426D01*
G01X298934D02*
X304174D01*
G01X319054Y-161926D02*
Y-179426D01*
G01X314032Y-161926D02*
X324076D01*
G01X333934D02*
X339174D01*
G01X336554D02*
Y-179426D01*
G01X333934D02*
X339174D01*
G01X354054D02*
X352307Y-179134D01*
X350779Y-177968D01*
X349469Y-176218D01*
X348595Y-174176D01*
X348159Y-171843D01*
Y-169509D01*
X348595Y-167176D01*
X349469Y-165134D01*
X350779Y-163385D01*
X352307Y-162218D01*
X354054Y-161926D01*
X355800Y-162218D01*
X357329Y-163385D01*
X358639Y-165134D01*
X359513Y-167176D01*
X359949Y-169509D01*
Y-171843D01*
X359513Y-174176D01*
X358639Y-176218D01*
X357329Y-177968D01*
X355800Y-179134D01*
X354054Y-179426D01*
G01X366532D02*
Y-161926D01*
X376576Y-179426D01*
Y-161926D01*
G01X408300Y-170093D02*
X409174Y-169218D01*
X409829Y-167760D01*
X410266Y-165717D01*
X409829Y-163968D01*
X408956Y-162801D01*
X407427Y-161926D01*
X401532D01*
Y-179426D01*
X408737D01*
X410266Y-178260D01*
X411139Y-176509D01*
X411576Y-174468D01*
X411139Y-172426D01*
X409829Y-170676D01*
X408300Y-170093D01*
X401532D01*
G01X424054Y-179426D02*
X422307Y-179134D01*
X420779Y-177968D01*
X419469Y-176218D01*
X418595Y-174176D01*
X418159Y-171843D01*
Y-169509D01*
X418595Y-167176D01*
X419469Y-165134D01*
X420779Y-163385D01*
X422307Y-162218D01*
X424054Y-161926D01*
X425800Y-162218D01*
X427329Y-163385D01*
X428639Y-165134D01*
X429513Y-167176D01*
X429949Y-169509D01*
Y-171843D01*
X429513Y-174176D01*
X428639Y-176218D01*
X427329Y-177968D01*
X425800Y-179134D01*
X424054Y-179426D01*
G01X436095D02*
X441554Y-161926D01*
X447013Y-179426D01*
G01X445047Y-173301D02*
X438060D01*
G01X454687Y-179426D02*
Y-161926D01*
X460146D01*
X461892Y-162801D01*
X462984Y-163968D01*
X463421Y-166301D01*
X462984Y-168635D01*
X461674Y-170093D01*
X460146Y-170968D01*
X454687D01*
G01X460146D02*
X463421Y-179426D01*
G01X471751D02*
Y-161926D01*
X476117D01*
X477864Y-162801D01*
X479174Y-163968D01*
X480266Y-165717D01*
X481139Y-167760D01*
X481357Y-170676D01*
X481139Y-173593D01*
X480266Y-175635D01*
X479174Y-177385D01*
X477864Y-178551D01*
X476117Y-179426D01*
X471751D01*
G01X208377Y-134426D02*
Y-116926D01*
X214054Y-131509D01*
X219731Y-116926D01*
Y-134426D01*
G01X231554D02*
X230244Y-134134D01*
X228934Y-132968D01*
X228060Y-130926D01*
X227624Y-128593D01*
X228060Y-126259D01*
X228934Y-124218D01*
X230244Y-123051D01*
X231554Y-122760D01*
X232864Y-123051D01*
X234174Y-124218D01*
X235047Y-126259D01*
X235266Y-128593D01*
X235047Y-130926D01*
X234174Y-132968D01*
X232864Y-134134D01*
X231554Y-134426D01*
G01X252984Y-116926D02*
Y-134426D01*
G01Y-131802D02*
X252111Y-133260D01*
X250800Y-134134D01*
X249272Y-134426D01*
X247526Y-133843D01*
X246216Y-132385D01*
X245342Y-130635D01*
X245124Y-128593D01*
X245342Y-126551D01*
X246216Y-124801D01*
X247526Y-123343D01*
X249272Y-122760D01*
X250800Y-123051D01*
X251892Y-123635D01*
X252984Y-124801D01*
G01X263279Y-126551D02*
X270266D01*
X269611Y-124509D01*
X268519Y-123343D01*
X266991Y-122760D01*
X265462Y-123051D01*
X264152Y-123926D01*
X263279Y-125968D01*
X262842Y-127718D01*
Y-129468D01*
X263279Y-131218D01*
X264371Y-132968D01*
X265681Y-134134D01*
X267209Y-134426D01*
X268737Y-133843D01*
X270266Y-132093D01*
G01X284054Y-134426D02*
Y-116926D01*
G01X536554Y-179426D02*
Y-161926D01*
X533934Y-165426D01*
G01Y-179426D02*
X539174D01*
G01X549906Y-164843D02*
X551216Y-163093D01*
X552744Y-162218D01*
X554491Y-161926D01*
X556674Y-162509D01*
X558202Y-163968D01*
X558639Y-165717D01*
X558421Y-167468D01*
X557547Y-168926D01*
X553181Y-171843D01*
X551216Y-173884D01*
X549906Y-176802D01*
X549469Y-179426D01*
X558639D01*
G01X566751Y-176802D02*
X568060Y-178260D01*
X569589Y-179134D01*
X571554Y-179426D01*
X573519Y-178843D01*
X575047Y-177676D01*
X576139Y-175635D01*
X576357Y-173301D01*
X575921Y-170968D01*
X574829Y-169509D01*
X573300Y-168343D01*
X571772Y-168051D01*
X570244Y-168343D01*
X568279Y-169509D01*
X568934Y-161926D01*
X574829D01*
G01X584906Y-164843D02*
X586216Y-163093D01*
X587744Y-162218D01*
X589491Y-161926D01*
X591674Y-162509D01*
X593202Y-163968D01*
X593639Y-165717D01*
X593421Y-167468D01*
X592547Y-168926D01*
X588181Y-171843D01*
X586216Y-173884D01*
X584906Y-176802D01*
X584469Y-179426D01*
X593639D01*
G01X601751Y-175926D02*
X603060Y-177968D01*
X604807Y-179134D01*
X606772Y-179426D01*
X608519Y-179134D01*
X610266Y-177676D01*
X611357Y-175926D01*
X611576Y-174176D01*
X611139Y-172135D01*
X609611Y-170676D01*
X608082Y-170093D01*
X606117D01*
G01X608082D02*
X609392Y-169218D01*
X610484Y-167760D01*
X610921Y-166010D01*
X610484Y-164259D01*
X609392Y-162801D01*
X607427Y-161926D01*
X605462Y-162218D01*
X603497Y-163385D01*
G01X523437Y-134426D02*
Y-116926D01*
X528677D01*
X530424Y-117801D01*
X531734Y-119843D01*
X532171Y-122176D01*
X531734Y-124509D01*
X530642Y-126259D01*
X528677Y-127135D01*
X523437D01*
G01X550107Y-118385D02*
X548797Y-117509D01*
X547269Y-116926D01*
X545522D01*
X543557Y-117801D01*
X542029Y-119259D01*
X540937Y-121010D01*
X540064Y-123926D01*
X539845Y-126551D01*
X540282Y-129176D01*
X540937Y-130926D01*
X542247Y-132676D01*
X543776Y-133843D01*
X545304Y-134426D01*
X546832D01*
X548361Y-133843D01*
X549671Y-132968D01*
X550763Y-131802D01*
G01X564550Y-125093D02*
X565424Y-124218D01*
X566079Y-122760D01*
X566516Y-120717D01*
X566079Y-118968D01*
X565206Y-117801D01*
X563677Y-116926D01*
X557782D01*
Y-134426D01*
X564987D01*
X566516Y-133260D01*
X567389Y-131509D01*
X567826Y-129468D01*
X567389Y-127426D01*
X566079Y-125676D01*
X564550Y-125093D01*
X557782D01*
G01X573754Y-140259D02*
X586854D01*
G01X592782Y-134426D02*
Y-116926D01*
X602826Y-134426D01*
Y-116926D01*
G01X615304Y-134426D02*
X613557Y-134134D01*
X612029Y-132968D01*
X610719Y-131218D01*
X609845Y-129176D01*
X609409Y-126843D01*
Y-124509D01*
X609845Y-122176D01*
X610719Y-120134D01*
X612029Y-118385D01*
X613557Y-117218D01*
X615304Y-116926D01*
X617050Y-117218D01*
X618579Y-118385D01*
X619889Y-120134D01*
X620763Y-122176D01*
X621199Y-124509D01*
Y-126843D01*
X620763Y-129176D01*
X619889Y-131218D01*
X618579Y-132968D01*
X617050Y-134134D01*
X615304Y-134426D01*
G01X697854Y-179426D02*
Y-161926D01*
X695234Y-165426D01*
G01Y-179426D02*
X700474D01*
G01X666145Y-116926D02*
X671604Y-134426D01*
X677063Y-116926D01*
G01X693471Y-134426D02*
X684737D01*
Y-116926D01*
X693471D01*
G01X689977Y-125384D02*
X684737D01*
G01X702237Y-134426D02*
Y-116926D01*
X707696D01*
X709442Y-117801D01*
X710534Y-118968D01*
X710971Y-121301D01*
X710534Y-123635D01*
X709224Y-125093D01*
X707696Y-125968D01*
X702237D01*
G01X707696D02*
X710971Y-134426D01*
G01X724104Y-135009D02*
X723667Y-134718D01*
Y-134134D01*
X724104Y-133843D01*
X724541Y-134134D01*
Y-134718D01*
X724104Y-135009D01*
G01X872308Y-170093D02*
X871434Y-169218D01*
X870779Y-167760D01*
X870342Y-165717D01*
X870779Y-163968D01*
X871652Y-162801D01*
X873181Y-161926D01*
X879076D01*
Y-179426D01*
X871871D01*
X870342Y-178260D01*
X869469Y-176509D01*
X869032Y-174468D01*
X869469Y-172426D01*
X870779Y-170676D01*
X872308Y-170093D01*
X879076D01*
G01X862231Y-179426D02*
Y-161926D01*
X856554Y-176509D01*
X850877Y-161926D01*
Y-179426D01*
G01X844513D02*
X839054Y-161926D01*
X833595Y-179426D01*
G01X835561Y-173301D02*
X842548D01*
G01X826139Y-177093D02*
X824392Y-178551D01*
X822427Y-179426D01*
X820681D01*
X818934Y-178551D01*
X817624Y-177093D01*
X816969Y-175051D01*
X817406Y-173010D01*
X818497Y-171259D01*
X820462Y-170093D01*
X823082Y-169509D01*
X824611Y-168343D01*
X825266Y-166301D01*
X824829Y-164259D01*
X823737Y-162801D01*
X822209Y-161926D01*
X820681D01*
X819152Y-162509D01*
X817842Y-163968D01*
G01X808857Y-179426D02*
Y-161926D01*
G01X800561D02*
X808857Y-172718D01*
G01X799251Y-179426D02*
X805146Y-167760D01*
G01X790937Y-116926D02*
Y-134426D01*
X799671D01*
G01X816734D02*
Y-122760D01*
G01Y-124801D02*
X815861Y-123635D01*
X814550Y-123051D01*
X813022Y-122760D01*
X811494Y-123343D01*
X810184Y-124509D01*
X809310Y-126259D01*
X808874Y-128593D01*
X809310Y-130926D01*
X810184Y-132676D01*
X811494Y-133843D01*
X813022Y-134426D01*
X814550Y-134134D01*
X815861Y-133260D01*
X816734Y-132093D01*
G01X825719Y-139676D02*
X827029Y-140259D01*
X828776Y-139676D01*
X829867Y-138510D01*
X830741Y-137051D01*
X832050Y-132385D01*
X834889Y-122760D01*
G01X827902D02*
X832050Y-132385D01*
G01X844529Y-126551D02*
X851516D01*
X850861Y-124509D01*
X849769Y-123343D01*
X848241Y-122760D01*
X846712Y-123051D01*
X845402Y-123926D01*
X844529Y-125968D01*
X844092Y-127718D01*
Y-129468D01*
X844529Y-131218D01*
X845621Y-132968D01*
X846931Y-134134D01*
X848459Y-134426D01*
X849987Y-133843D01*
X851516Y-132093D01*
G01X862247Y-134426D02*
Y-122760D01*
G01Y-125093D02*
X863339Y-123926D01*
X864431Y-123051D01*
X865959Y-122760D01*
X867050Y-123051D01*
X868361Y-123926D01*
G01X879529Y-132385D02*
X880621Y-133551D01*
X882149Y-134426D01*
X883459D01*
X884769Y-133843D01*
X885642Y-132968D01*
X886079Y-131802D01*
X885861Y-130051D01*
X884987Y-129176D01*
X881057Y-127426D01*
X880184Y-125384D01*
X880621Y-123926D01*
X881494Y-123051D01*
X882804Y-122760D01*
X884114Y-123051D01*
X885424Y-123926D01*
G01X924737Y-175926D02*
X925829Y-177676D01*
X927139Y-178843D01*
X928667Y-179426D01*
X930414Y-178843D01*
X931724Y-177676D01*
X933034Y-175926D01*
X933471Y-173593D01*
Y-161926D01*
G01X946604Y-179426D02*
X944857Y-179134D01*
X943329Y-177968D01*
X942019Y-176218D01*
X941145Y-174176D01*
X940709Y-171843D01*
Y-169509D01*
X941145Y-167176D01*
X942019Y-165134D01*
X943329Y-163385D01*
X944857Y-162218D01*
X946604Y-161926D01*
X948350Y-162218D01*
X949879Y-163385D01*
X951189Y-165134D01*
X952063Y-167176D01*
X952499Y-169509D01*
Y-171843D01*
X952063Y-174176D01*
X951189Y-176218D01*
X949879Y-177968D01*
X948350Y-179134D01*
X946604Y-179426D01*
G01X959519Y-177093D02*
X961266Y-178551D01*
X963231Y-179426D01*
X964977D01*
X966724Y-178551D01*
X968034Y-177093D01*
X968689Y-175051D01*
X968252Y-173010D01*
X967161Y-171259D01*
X965196Y-170093D01*
X962576Y-169509D01*
X961047Y-168343D01*
X960392Y-166301D01*
X960829Y-164259D01*
X961921Y-162801D01*
X963449Y-161926D01*
X964977D01*
X966506Y-162509D01*
X967816Y-163968D01*
G01X985971Y-179426D02*
X977237D01*
Y-161926D01*
X985971D01*
G01X982477Y-170384D02*
X977237D01*
G01X994737Y-179426D02*
Y-161926D01*
X999977D01*
X1001724Y-162801D01*
X1003034Y-164843D01*
X1003471Y-167176D01*
X1003034Y-169509D01*
X1001942Y-171259D01*
X999977Y-172135D01*
X994737D01*
G01X1012019Y-179426D02*
Y-161926D01*
G01X1021189D02*
Y-179426D01*
G01Y-170676D02*
X1012019D01*
G01X1047237Y-161926D02*
Y-179426D01*
X1055971D01*
G01X1063645D02*
X1069104Y-161926D01*
X1074563Y-179426D01*
G01X1072597Y-173301D02*
X1065610D01*
G01X1081801Y-161926D02*
Y-174468D01*
X1082674Y-177093D01*
X1084421Y-178843D01*
X1086604Y-179426D01*
X1088787Y-178843D01*
X1090534Y-177093D01*
X1091407Y-174468D01*
Y-161926D01*
G01X941801Y-134426D02*
Y-116926D01*
X946167D01*
X947914Y-117801D01*
X949224Y-118968D01*
X950316Y-120717D01*
X951189Y-122760D01*
X951407Y-125676D01*
X951189Y-128593D01*
X950316Y-130635D01*
X949224Y-132385D01*
X947914Y-133551D01*
X946167Y-134426D01*
X941801D01*
G01X960829Y-126551D02*
X967816D01*
X967161Y-124509D01*
X966069Y-123343D01*
X964541Y-122760D01*
X963012Y-123051D01*
X961702Y-123926D01*
X960829Y-125968D01*
X960392Y-127718D01*
Y-129468D01*
X960829Y-131218D01*
X961921Y-132968D01*
X963231Y-134134D01*
X964759Y-134426D01*
X966287Y-133843D01*
X967816Y-132093D01*
G01X978329Y-132385D02*
X979421Y-133551D01*
X980949Y-134426D01*
X982259D01*
X983569Y-133843D01*
X984442Y-132968D01*
X984879Y-131802D01*
X984661Y-130051D01*
X983787Y-129176D01*
X979857Y-127426D01*
X978984Y-125384D01*
X979421Y-123926D01*
X980294Y-123051D01*
X981604Y-122760D01*
X982914Y-123051D01*
X984224Y-123926D01*
G01X999104Y-122760D02*
Y-134426D01*
G01Y-118093D02*
X998667Y-117801D01*
Y-117218D01*
X999104Y-116926D01*
X999541Y-117218D01*
Y-117801D01*
X999104Y-118093D01*
G01X1013547Y-138801D02*
X1015076Y-139968D01*
X1016822Y-140259D01*
X1018350Y-139968D01*
X1019661Y-138510D01*
X1020534Y-136468D01*
Y-122760D01*
G01Y-125093D02*
X1019661Y-123926D01*
X1018350Y-123051D01*
X1016822Y-122760D01*
X1015076Y-123343D01*
X1013984Y-124509D01*
X1013110Y-126551D01*
X1012674Y-128593D01*
X1012892Y-130343D01*
X1013766Y-132385D01*
X1015076Y-133843D01*
X1016822Y-134426D01*
X1018132Y-134134D01*
X1019661Y-132968D01*
X1020534Y-131802D01*
G01X1030392Y-134426D02*
Y-122760D01*
G01Y-125676D02*
X1031266Y-124218D01*
X1032576Y-123051D01*
X1034322Y-122760D01*
X1035850Y-123051D01*
X1037161Y-124218D01*
X1037816Y-126259D01*
Y-134426D01*
G01X1048329Y-126551D02*
X1055316D01*
X1054661Y-124509D01*
X1053569Y-123343D01*
X1052041Y-122760D01*
X1050512Y-123051D01*
X1049202Y-123926D01*
X1048329Y-125968D01*
X1047892Y-127718D01*
Y-129468D01*
X1048329Y-131218D01*
X1049421Y-132968D01*
X1050731Y-134134D01*
X1052259Y-134426D01*
X1053787Y-133843D01*
X1055316Y-132093D01*
G01X1066047Y-134426D02*
Y-122760D01*
G01Y-125093D02*
X1067139Y-123926D01*
X1068231Y-123051D01*
X1069759Y-122760D01*
X1070850Y-123051D01*
X1072161Y-123926D01*
G01X1112804Y-179426D02*
Y-161926D01*
X1110184Y-165426D01*
G01Y-179426D02*
X1115424D01*
G01X1130304Y-161926D02*
X1128557Y-162509D01*
X1127247Y-163968D01*
X1126374Y-165717D01*
X1125719Y-168051D01*
X1125501Y-170676D01*
X1125719Y-173301D01*
X1126374Y-175635D01*
X1127247Y-177385D01*
X1128557Y-178843D01*
X1130304Y-179426D01*
X1132050Y-178843D01*
X1133361Y-177385D01*
X1134234Y-175635D01*
X1134889Y-173301D01*
X1135107Y-170676D01*
X1134889Y-168051D01*
X1134234Y-165717D01*
X1133361Y-163968D01*
X1132050Y-162509D01*
X1130304Y-161926D01*
G01X1143874Y-180009D02*
X1151734Y-161926D01*
G01X1165304Y-179426D02*
Y-161926D01*
X1162684Y-165426D01*
G01Y-179426D02*
X1167924D01*
G01X1179092Y-177385D02*
X1180621Y-178843D01*
X1182367Y-179426D01*
X1184114Y-178843D01*
X1185642Y-177093D01*
X1186734Y-174468D01*
X1187171Y-171843D01*
Y-168635D01*
X1186734Y-166010D01*
X1185642Y-163676D01*
X1184332Y-162509D01*
X1182804Y-161926D01*
X1181057Y-162509D01*
X1179747Y-163676D01*
X1178874Y-165426D01*
X1178437Y-167760D01*
X1178874Y-169801D01*
X1179966Y-171843D01*
X1181276Y-173010D01*
X1182804Y-173301D01*
X1184550Y-172718D01*
X1185861Y-171259D01*
X1187171Y-168635D01*
G01X1196374Y-180009D02*
X1204234Y-161926D01*
G01X1213656Y-164843D02*
X1214966Y-163093D01*
X1216494Y-162218D01*
X1218241Y-161926D01*
X1220424Y-162509D01*
X1221952Y-163968D01*
X1222389Y-165717D01*
X1222171Y-167468D01*
X1221297Y-168926D01*
X1216931Y-171843D01*
X1214966Y-173884D01*
X1213656Y-176802D01*
X1213219Y-179426D01*
X1222389D01*
G01X1235304Y-161926D02*
X1233557Y-162509D01*
X1232247Y-163968D01*
X1231374Y-165717D01*
X1230719Y-168051D01*
X1230501Y-170676D01*
X1230719Y-173301D01*
X1231374Y-175635D01*
X1232247Y-177385D01*
X1233557Y-178843D01*
X1235304Y-179426D01*
X1237050Y-178843D01*
X1238361Y-177385D01*
X1239234Y-175635D01*
X1239889Y-173301D01*
X1240107Y-170676D01*
X1239889Y-168051D01*
X1239234Y-165717D01*
X1238361Y-163968D01*
X1237050Y-162509D01*
X1235304Y-161926D01*
G01X1252804Y-179426D02*
Y-161926D01*
X1250184Y-165426D01*
G01Y-179426D02*
X1255424D01*
G01X1266156Y-164843D02*
X1267466Y-163093D01*
X1268994Y-162218D01*
X1270741Y-161926D01*
X1272924Y-162509D01*
X1274452Y-163968D01*
X1274889Y-165717D01*
X1274671Y-167468D01*
X1273797Y-168926D01*
X1269431Y-171843D01*
X1267466Y-173884D01*
X1266156Y-176802D01*
X1265719Y-179426D01*
X1274889D01*
G01X1160501Y-134426D02*
Y-116926D01*
X1164867D01*
X1166614Y-117801D01*
X1167924Y-118968D01*
X1169016Y-120717D01*
X1169889Y-122760D01*
X1170107Y-125676D01*
X1169889Y-128593D01*
X1169016Y-130635D01*
X1167924Y-132385D01*
X1166614Y-133551D01*
X1164867Y-134426D01*
X1160501D01*
G01X1186734D02*
Y-122760D01*
G01Y-124801D02*
X1185861Y-123635D01*
X1184550Y-123051D01*
X1183022Y-122760D01*
X1181494Y-123343D01*
X1180184Y-124509D01*
X1179310Y-126259D01*
X1178874Y-128593D01*
X1179310Y-130926D01*
X1180184Y-132676D01*
X1181494Y-133843D01*
X1183022Y-134426D01*
X1184550Y-134134D01*
X1185861Y-133260D01*
X1186734Y-132093D01*
G01X1200304Y-116926D02*
Y-134426D01*
G01X1197247Y-122760D02*
X1203361D01*
G01X1214529Y-126551D02*
X1221516D01*
X1220861Y-124509D01*
X1219769Y-123343D01*
X1218241Y-122760D01*
X1216712Y-123051D01*
X1215402Y-123926D01*
X1214529Y-125968D01*
X1214092Y-127718D01*
Y-129468D01*
X1214529Y-131218D01*
X1215621Y-132968D01*
X1216931Y-134134D01*
X1218459Y-134426D01*
X1219987Y-133843D01*
X1221516Y-132093D01*
G54D13*
X-25005Y133422D03*
Y173422D03*
Y213422D03*
Y253422D03*
G54D14*
Y283072D03*
G54D15*
X-27555Y302202D03*
Y307202D03*
Y312202D03*
Y317202D03*
Y322202D03*
Y327202D03*
Y332202D03*
Y337202D03*
Y342202D03*
Y347202D03*
Y352202D03*
Y357202D03*
G54D16*
X-2722Y341000D03*
X1635Y347764D03*
X46898Y152936D03*
Y117936D03*
X47398Y214936D03*
X46898Y182936D03*
X48398Y274936D03*
X26500Y330436D03*
X20898Y325436D03*
X49398Y326436D03*
X20398Y309936D03*
X14000Y336000D03*
X53398Y388936D03*
X76000Y32000D03*
X73000Y94500D03*
X114398Y308936D03*
X78398Y371936D03*
X67398Y416936D03*
X189398Y115936D03*
X208398Y433436D03*
X248898Y35936D03*
X247898Y234936D03*
X282398Y312436D03*
X347898Y117436D03*
X365398Y35936D03*
X393241Y239988D03*
X394022Y308262D03*
X364398Y430936D03*
X507398Y196436D03*
X485398Y372436D03*
X469046Y443685D03*
X509898Y431936D03*
X525898Y33436D03*
X568691Y66413D03*
X526398Y116936D03*
X543000Y197500D03*
X534898Y261436D03*
X536398Y418936D03*
X610000Y100000D03*
X612747Y93023D03*
X579500Y333500D03*
X605398Y409436D03*
G54D17*
X570709Y161889D03*
X580709D03*
X570709Y214409D03*
X580709D03*
X570709Y204409D03*
X580709D03*
X570709Y191889D03*
X580709D03*
X570709Y181889D03*
X580709D03*
X570709Y171889D03*
X580709D03*
X570709Y244409D03*
X580709D03*
X570709Y276929D03*
X580709D03*
X570709Y266929D03*
X580709D03*
X570709Y256929D03*
X580709D03*
X570709Y234409D03*
X580709D03*
X570709Y224409D03*
X580709D03*
X570709Y286929D03*
X580709D03*
X590709Y161889D03*
X600709D03*
X590709Y214409D03*
X600709D03*
X590709Y204409D03*
X600709D03*
X590709Y191889D03*
X600709D03*
X590709Y181889D03*
X600709D03*
X590709Y171889D03*
X600709D03*
X590709Y244409D03*
X600709D03*
X590709Y276929D03*
X600709D03*
X590709Y266929D03*
X600709D03*
X590709Y256929D03*
X600709D03*
X590709Y234409D03*
X600709D03*
X590709Y224409D03*
X600709D03*
X590709Y286929D03*
X600709D03*
G54D18*
X599055Y59055D03*
Y90551D03*
G54D19*
X596102Y66929D03*
X602008Y74803D03*
X596102Y82677D03*
M02*
